(kicad_pcb
	(version 20260206)
	(generator "pcbnew")
	(generator_version "10.0")
	(general
		(thickness 1.6)
		(legacy_teardrops no)
	)
	(paper "A4")
	(title_block
		(title "03242023_DA0F0TMBIJ0_F0T_Motherboard_J_brd_V01_OCP.brd")
		(comment 1 "Grand Teton / footprints 5666-5671 of 6105")
	)
	(layers
		(0 "F.Cu" signal "TOP")
		(4 "In1.Cu" signal "GND")
		(6 "In2.Cu" signal "IN1")
		(8 "In3.Cu" signal "GND1")
		(10 "In4.Cu" signal "IN2")
		(12 "In5.Cu" signal "GND2")
		(14 "In6.Cu" signal "IN3")
		(16 "In7.Cu" signal "GND3")
		(18 "In8.Cu" signal "VCC")
		(20 "In9.Cu" signal "VCC1")
		(22 "In10.Cu" signal "GND4")
		(24 "In11.Cu" signal "IN4")
		(26 "In12.Cu" signal "GND5")
		(28 "In13.Cu" signal "IN5")
		(30 "In14.Cu" signal "GND6")
		(32 "In15.Cu" signal "IN6")
		(34 "In16.Cu" signal "GND7")
		(2 "B.Cu" signal "BOTTOM")
		(9 "F.Adhes" user "F.Adhesive")
		(11 "B.Adhes" user "B.Adhesive")
		(13 "F.Paste" user "Package Geometry/Pastemask Top")
		(15 "B.Paste" user "Package Geometry/Pastemask Bottom")
		(5 "F.SilkS" user "Ref Des/Silkscreen Top")
		(7 "B.SilkS" user "Ref Des/Silkscreen Bottom")
		(1 "F.Mask" user "Board Geometry/Soldermask Top")
		(3 "B.Mask" user "Board Geometry/Soldermask Bottom")
		(17 "Dwgs.User" user "User.Drawings")
		(19 "Cmts.User" user "User.Comments")
		(21 "Eco1.User" user "User.Eco1")
		(23 "Eco2.User" user "User.Eco2")
		(25 "Edge.Cuts" user "Board Geometry/Outline")
		(27 "Margin" user)
		(31 "F.CrtYd" user "Package Geometry/Place Bound Top")
		(29 "B.CrtYd" user "Package Geometry/Place Bound Bottom")
		(35 "F.Fab" user "Ref Des/Assembly Top")
		(33 "B.Fab" user "Ref Des/Assembly Bottom")
	)
	(footprint ""
		(layer "B.Cu")
		(at 340.374986 -328.298048 -90)
		(property "Reference" "PC266_P0_6"
			(at 0 0 90)
			(layer "B.SilkS")
			(hide yes)
			(effects
				(font
					(size 1.27 1.27)
				)
				(justify mirror)
			)
		)
		(property "Value" ""
			(at 0 0 90)
			(layer "B.Fab")
			(effects
				(font
					(size 1.27 1.27)
				)
				(justify mirror)
			)
		)
		(duplicate_pad_numbers_are_jumpers no)
		(fp_line
			(start -1.524 0.762)
			(end 1.524 0.762)
			(stroke
				(width 0.1524)
				(type default)
			)
			(layer "B.SilkS")
		)
		(fp_line
			(start 1.524 0.762)
			(end 1.524 -0.762)
			(stroke
				(width 0.1524)
				(type default)
			)
			(layer "B.SilkS")
		)
		(fp_line
			(start -1.524 -0.762)
			(end -1.524 0.762)
			(stroke
				(width 0.1524)
				(type default)
			)
			(layer "B.SilkS")
		)
		(fp_line
			(start 1.524 -0.762)
			(end -1.524 -0.762)
			(stroke
				(width 0.1524)
				(type default)
			)
			(layer "B.SilkS")
		)
		(fp_line
			(start -1.1049 0.724916)
			(end -1.1049 -0.724916)
			(stroke
				(width 0.1)
				(type default)
			)
			(layer "B.Fab")
		)
		(fp_line
			(start 1.1049 0.724916)
			(end -1.1049 0.724916)
			(stroke
				(width 0.1)
				(type default)
			)
			(layer "B.Fab")
		)
		(fp_line
			(start -1.1049 -0.724916)
			(end 1.1049 -0.724916)
			(stroke
				(width 0.1)
				(type default)
			)
			(layer "B.Fab")
		)
		(fp_line
			(start 1.1049 -0.724916)
			(end 1.1049 0.724916)
			(stroke
				(width 0.1)
				(type default)
			)
			(layer "B.Fab")
		)
		(pad "1" smd rect
			(at 0.889 0 270)
			(size 1.016 1.27)
			(layers "B.Cu" "B.Mask" "B.Paste")
			(net "PVCCIN_CPU0")
		)
		(pad "2" smd rect
			(at -0.889 0 270)
			(size 1.016 1.27)
			(layers "B.Cu" "B.Mask" "B.Paste")
			(net "GND")
		)
	)
	(footprint ""
		(layer "B.Cu")
		(at 157.02788 -118.836948)
		(property "Reference" "R3175"
			(at 0 0 0)
			(layer "B.SilkS")
			(hide yes)
			(effects
				(font
					(size 1.27 1.27)
				)
				(justify mirror)
			)
		)
		(property "Value" ""
			(at 0 0 0)
			(layer "B.Fab")
			(effects
				(font
					(size 1.27 1.27)
				)
				(justify mirror)
			)
		)
		(duplicate_pad_numbers_are_jumpers no)
		(fp_line
			(start -0.7874 -0.4064)
			(end -0.7874 0.4064)
			(stroke
				(width 0.1524)
				(type default)
			)
			(layer "B.SilkS")
		)
		(fp_line
			(start -0.7874 0.4064)
			(end 0.7874 0.4064)
			(stroke
				(width 0.1524)
				(type default)
			)
			(layer "B.SilkS")
		)
		(fp_line
			(start 0.7874 -0.4064)
			(end -0.7874 -0.4064)
			(stroke
				(width 0.1524)
				(type default)
			)
			(layer "B.SilkS")
		)
		(fp_line
			(start 0.7874 0.4064)
			(end 0.7874 -0.4064)
			(stroke
				(width 0.1524)
				(type default)
			)
			(layer "B.SilkS")
		)
		(fp_line
			(start -0.67945 -0.3048)
			(end -0.67945 0.3048)
			(stroke
				(width 0.1)
				(type default)
			)
			(layer "B.Fab")
		)
		(fp_line
			(start -0.67945 0.3048)
			(end -0.120396 0.3048)
			(stroke
				(width 0.1)
				(type default)
			)
			(layer "B.Fab")
		)
		(fp_line
			(start -0.12065 -0.3048)
			(end -0.67945 -0.3048)
			(stroke
				(width 0.1)
				(type default)
			)
			(layer "B.Fab")
		)
		(fp_line
			(start -0.12065 -0.2794)
			(end -0.12065 -0.3048)
			(stroke
				(width 0.1)
				(type default)
			)
			(layer "B.Fab")
		)
		(fp_line
			(start -0.120396 0.2794)
			(end 0.12065 0.2794)
			(stroke
				(width 0.1)
				(type default)
			)
			(layer "B.Fab")
		)
		(fp_line
			(start -0.120396 0.3048)
			(end -0.120396 0.2794)
			(stroke
				(width 0.1)
				(type default)
			)
			(layer "B.Fab")
		)
		(fp_line
			(start 0.12065 -0.305054)
			(end 0.12065 -0.2794)
			(stroke
				(width 0.1)
				(type default)
			)
			(layer "B.Fab")
		)
		(fp_line
			(start 0.12065 -0.2794)
			(end -0.12065 -0.2794)
			(stroke
				(width 0.1)
				(type default)
			)
			(layer "B.Fab")
		)
		(fp_line
			(start 0.12065 0.2794)
			(end 0.12065 0.3048)
			(stroke
				(width 0.1)
				(type default)
			)
			(layer "B.Fab")
		)
		(fp_line
			(start 0.12065 0.3048)
			(end 0.67945 0.3048)
			(stroke
				(width 0.1)
				(type default)
			)
			(layer "B.Fab")
		)
		(fp_line
			(start 0.67945 -0.305054)
			(end 0.12065 -0.305054)
			(stroke
				(width 0.1)
				(type default)
			)
			(layer "B.Fab")
		)
		(fp_line
			(start 0.67945 0.3048)
			(end 0.67945 -0.305054)
			(stroke
				(width 0.1)
				(type default)
			)
			(layer "B.Fab")
		)
		(pad "1" smd circle
			(at 0.40005 0 180)
			(size 0 0)
			(layers "B.Cu" "B.Mask" "B.Paste")
			(net "SGPIO_OCP_V3_2_DATAOUT")
		)
		(pad "2" smd circle
			(at -0.40005 0 180)
			(size 0 0)
			(layers "B.Cu" "B.Mask" "B.Paste")
			(net "GND")
		)
	)
	(footprint ""
		(layer "B.Cu")
		(at 522.584426 -303.621948 -90)
		(property "Reference" "X11"
			(at 3.493008 2.66319 270)
			(unlocked yes)
			(layer "B.SilkS")
			(effects
				(font
					(size 0.7874 0.5842)
					(thickness 0.1524)
				)
				(justify left mirror)
			)
		)
		(property "Value" ""
			(at 0 0 90)
			(layer "B.Fab")
			(effects
				(font
					(size 1.27 1.27)
				)
				(justify mirror)
			)
		)
		(property "Device Type" "TP_TDR_4P_FTS_TH-TP_TDR_4P_DIPA"
			(at -1.30175 1.27 180)
			(unlocked yes)
			(layer "B.Fab")
			(hide yes)
			(effects
				(font
					(size 0.635 0.4064)
					(thickness 0.1524)
				)
				(justify mirror)
			)
		)
		(property "User Part Number" "N_A"
			(at -1.30175 1.27 180)
			(unlocked yes)
			(layer "Cmts.User")
			(hide yes)
			(effects
				(font
					(size 0.635 0.4064)
					(thickness 0.1524)
				)
				(justify mirror)
			)
		)
		(duplicate_pad_numbers_are_jumpers no)
		(fp_line
			(start -2.54 3.81)
			(end -2.54 3.6703)
			(stroke
				(width 0.1524)
				(type default)
			)
			(layer "B.SilkS")
		)
		(fp_line
			(start 0 3.81)
			(end -2.54 3.81)
			(stroke
				(width 0.1524)
				(type default)
			)
			(layer "B.SilkS")
		)
		(fp_line
			(start 0 3.175)
			(end 0 3.81)
			(stroke
				(width 0.1524)
				(type default)
			)
			(layer "B.SilkS")
		)
		(fp_line
			(start -2.54 1.4097)
			(end -2.54 1.1303)
			(stroke
				(width 0.1524)
				(type default)
			)
			(layer "B.SilkS")
		)
		(fp_line
			(start 0 0.635)
			(end 0 1.905)
			(stroke
				(width 0.1524)
				(type default)
			)
			(layer "B.SilkS")
		)
		(fp_line
			(start -2.54 -1.1303)
			(end -2.54 -1.27)
			(stroke
				(width 0.1524)
				(type default)
			)
			(layer "B.SilkS")
		)
		(fp_line
			(start -2.54 -1.27)
			(end 0 -1.27)
			(stroke
				(width 0.1524)
				(type default)
			)
			(layer "B.SilkS")
		)
		(fp_line
			(start 0 -1.27)
			(end 0 -0.635)
			(stroke
				(width 0.1524)
				(type default)
			)
			(layer "B.SilkS")
		)
		(fp_poly
			(pts
				(xy 2.812034 -0.762) (xy 2.812034 0.762) (xy 1.288034 0)
			)
			(stroke
				(width 0)
				(type default)
			)
			(fill yes)
			(layer "B.SilkS")
		)
		(fp_line
			(start -2.54 3.81)
			(end -2.54 -1.27)
			(stroke
				(width 0.1)
				(type default)
			)
			(layer "B.Fab")
		)
		(fp_line
			(start 0 3.81)
			(end -2.54 3.81)
			(stroke
				(width 0.1)
				(type default)
			)
			(layer "B.Fab")
		)
		(fp_line
			(start -2.54 -1.27)
			(end 0 -1.27)
			(stroke
				(width 0.1)
				(type default)
			)
			(layer "B.Fab")
		)
		(fp_line
			(start 0 -1.27)
			(end 0 3.81)
			(stroke
				(width 0.1)
				(type default)
			)
			(layer "B.Fab")
		)
		(fp_poly
			(pts
				(xy 0.761746 0) (xy 2.285746 -0.762) (xy 2.285746 0.762)
			)
			(stroke
				(width 0)
				(type default)
			)
			(fill yes)
			(layer "B.Fab")
		)
		(pad "1" thru_hole circle
			(at 0 0 90)
			(size 1.0033 1.0033)
			(drill 0.249936)
			(layers "*.Cu" "*.Mask")
			(remove_unused_layers no)
			(net "TDR_DIFF_85_IN4_DN")
			(clearance 0.10795)
			(padstack
				(mode front_inner_back)
				(layer "Inner"
					(shape circle)
					(size 0.8001 0.8001)
					(clearance 0.1524)
				)
				(layer "B.Cu"
					(shape circle)
					(size 1.0033 1.0033)
					(thermal_gap 0.10795)
					(clearance 0.10795)
				)
			)
		)
		(pad "2" thru_hole circle
			(at -2.54 0 90)
			(size 1.9939 1.9939)
			(drill 0.249936)
			(layers "*.Cu" "*.Mask")
			(remove_unused_layers no)
			(net "T1_GND")
			(clearance 0.10795)
			(padstack
				(mode front_inner_back)
				(layer "Inner"
					(shape circle)
					(size 0.8001 0.8001)
					(clearance 0.1524)
				)
				(layer "B.Cu"
					(shape circle)
					(size 1.9939 1.9939)
					(thermal_gap 0.10795)
					(clearance 0.10795)
				)
			)
		)
		(pad "3" thru_hole circle
			(at -2.54 2.54 90)
			(size 1.9939 1.9939)
			(drill 0.249936)
			(layers "*.Cu" "*.Mask")
			(remove_unused_layers no)
			(net "T1_GND")
			(clearance 0.10795)
			(padstack
				(mode front_inner_back)
				(layer "Inner"
					(shape circle)
					(size 0.8001 0.8001)
					(clearance 0.1524)
				)
				(layer "B.Cu"
					(shape circle)
					(size 1.9939 1.9939)
					(thermal_gap 0.10795)
					(clearance 0.10795)
				)
			)
		)
		(pad "4" thru_hole circle
			(at 0 2.54 90)
			(size 1.0033 1.0033)
			(drill 0.249936)
			(layers "*.Cu" "*.Mask")
			(remove_unused_layers no)
			(net "TDR_DIFF_85_IN4_DP")
			(clearance 0.10795)
			(padstack
				(mode front_inner_back)
				(layer "Inner"
					(shape circle)
					(size 0.8001 0.8001)
					(clearance 0.1524)
				)
				(layer "B.Cu"
					(shape circle)
					(size 1.0033 1.0033)
					(thermal_gap 0.10795)
					(clearance 0.10795)
				)
			)
		)
	)
	(footprint ""
		(layer "B.Cu")
		(at 363.135418 -296.054526 180)
		(property "Reference" "C394"
			(at 0 0 0)
			(layer "B.SilkS")
			(hide yes)
			(effects
				(font
					(size 1.27 1.27)
				)
				(justify mirror)
			)
		)
		(property "Value" ""
			(at 0 0 0)
			(layer "B.Fab")
			(effects
				(font
					(size 1.27 1.27)
				)
				(justify mirror)
			)
		)
		(duplicate_pad_numbers_are_jumpers no)
		(fp_line
			(start 1.524 0.762)
			(end 1.524 -0.762)
			(stroke
				(width 0.1524)
				(type default)
			)
			(layer "B.SilkS")
		)
		(fp_line
			(start 1.524 -0.762)
			(end -1.524 -0.762)
			(stroke
				(width 0.1524)
				(type default)
			)
			(layer "B.SilkS")
		)
		(fp_line
			(start -1.524 0.762)
			(end 1.524 0.762)
			(stroke
				(width 0.1524)
				(type default)
			)
			(layer "B.SilkS")
		)
		(fp_line
			(start -1.524 -0.762)
			(end -1.524 0.762)
			(stroke
				(width 0.1524)
				(type default)
			)
			(layer "B.SilkS")
		)
		(fp_line
			(start 1.1049 0.724916)
			(end -1.1049 0.724916)
			(stroke
				(width 0.1)
				(type default)
			)
			(layer "B.Fab")
		)
		(fp_line
			(start 1.1049 -0.724916)
			(end 1.1049 0.724916)
			(stroke
				(width 0.1)
				(type default)
			)
			(layer "B.Fab")
		)
		(fp_line
			(start -1.1049 0.724916)
			(end -1.1049 -0.724916)
			(stroke
				(width 0.1)
				(type default)
			)
			(layer "B.Fab")
		)
		(fp_line
			(start -1.1049 -0.724916)
			(end 1.1049 -0.724916)
			(stroke
				(width 0.1)
				(type default)
			)
			(layer "B.Fab")
		)
		(pad "1" smd rect
			(at 0.889 0 180)
			(size 1.016 1.27)
			(layers "B.Cu" "B.Mask" "B.Paste")
			(net "PVCCIN_CPU0")
		)
		(pad "2" smd rect
			(at -0.889 0 180)
			(size 1.016 1.27)
			(layers "B.Cu" "B.Mask" "B.Paste")
			(net "GND")
		)
	)
	(footprint ""
		(layer "B.Cu")
		(at 420.453312 -366.454944 180)
		(property "Reference" "PC1675"
			(at 0 0 0)
			(layer "B.SilkS")
			(hide yes)
			(effects
				(font
					(size 1.27 1.27)
				)
				(justify mirror)
			)
		)
		(property "Value" ""
			(at 0 0 0)
			(layer "B.Fab")
			(effects
				(font
					(size 1.27 1.27)
				)
				(justify mirror)
			)
		)
		(duplicate_pad_numbers_are_jumpers no)
		(fp_line
			(start 1.524 0.762)
			(end 1.524 -0.762)
			(stroke
				(width 0.1524)
				(type default)
			)
			(layer "B.SilkS")
		)
		(fp_line
			(start 1.524 -0.762)
			(end -1.524 -0.762)
			(stroke
				(width 0.1524)
				(type default)
			)
			(layer "B.SilkS")
		)
		(fp_line
			(start -1.524 0.762)
			(end 1.524 0.762)
			(stroke
				(width 0.1524)
				(type default)
			)
			(layer "B.SilkS")
		)
		(fp_line
			(start -1.524 -0.762)
			(end -1.524 0.762)
			(stroke
				(width 0.1524)
				(type default)
			)
			(layer "B.SilkS")
		)
		(fp_line
			(start 1.1049 0.724916)
			(end -1.1049 0.724916)
			(stroke
				(width 0.1)
				(type default)
			)
			(layer "B.Fab")
		)
		(fp_line
			(start 1.1049 -0.724916)
			(end 1.1049 0.724916)
			(stroke
				(width 0.1)
				(type default)
			)
			(layer "B.Fab")
		)
		(fp_line
			(start -1.1049 0.724916)
			(end -1.1049 -0.724916)
			(stroke
				(width 0.1)
				(type default)
			)
			(layer "B.Fab")
		)
		(fp_line
			(start -1.1049 -0.724916)
			(end 1.1049 -0.724916)
			(stroke
				(width 0.1)
				(type default)
			)
			(layer "B.Fab")
		)
		(pad "1" smd rect
			(at 0.889 0 180)
			(size 1.016 1.27)
			(layers "B.Cu" "B.Mask" "B.Paste")
			(net "SW_P12V_PVCCFA_EHV_FIVRA_CPU0_R")
		)
		(pad "2" smd rect
			(at -0.889 0 180)
			(size 1.016 1.27)
			(layers "B.Cu" "B.Mask" "B.Paste")
			(net "GND")
		)
	)
	(footprint ""
		(layer "B.Cu")
		(at 299.679868 -198.197978 -90)
		(property "Reference" "R4296"
			(at 0 0 90)
			(layer "B.SilkS")
			(hide yes)
			(effects
				(font
					(size 1.27 1.27)
				)
				(justify mirror)
			)
		)
		(property "Value" ""
			(at 0 0 90)
			(layer "B.Fab")
			(effects
				(font
					(size 1.27 1.27)
				)
				(justify mirror)
			)
		)
		(duplicate_pad_numbers_are_jumpers no)
		(fp_line
			(start -0.7874 0.4064)
			(end 0.7874 0.4064)
			(stroke
				(width 0.1524)
				(type default)
			)
			(layer "B.SilkS")
		)
		(fp_line
			(start 0.7874 0.4064)
			(end 0.7874 -0.4064)
			(stroke
				(width 0.1524)
				(type default)
			)
			(layer "B.SilkS")
		)
		(fp_line
			(start -0.7874 -0.4064)
			(end -0.7874 0.4064)
			(stroke
				(width 0.1524)
				(type default)
			)
			(layer "B.SilkS")
		)
		(fp_line
			(start 0.7874 -0.4064)
			(end -0.7874 -0.4064)
			(stroke
				(width 0.1524)
				(type default)
			)
			(layer "B.SilkS")
		)
		(fp_line
			(start -0.67945 0.3048)
			(end -0.120396 0.3048)
			(stroke
				(width 0.1)
				(type default)
			)
			(layer "B.Fab")
		)
		(fp_line
			(start -0.120396 0.3048)
			(end -0.120396 0.2794)
			(stroke
				(width 0.1)
				(type default)
			)
			(layer "B.Fab")
		)
		(fp_line
			(start 0.12065 0.3048)
			(end 0.67945 0.3048)
			(stroke
				(width 0.1)
				(type default)
			)
			(layer "B.Fab")
		)
		(fp_line
			(start 0.67945 0.3048)
			(end 0.67945 -0.305054)
			(stroke
				(width 0.1)
				(type default)
			)
			(layer "B.Fab")
		)
		(fp_line
			(start -0.120396 0.2794)
			(end 0.12065 0.2794)
			(stroke
				(width 0.1)
				(type default)
			)
			(layer "B.Fab")
		)
		(fp_line
			(start 0.12065 0.2794)
			(end 0.12065 0.3048)
			(stroke
				(width 0.1)
				(type default)
			)
			(layer "B.Fab")
		)
		(fp_line
			(start -0.12065 -0.2794)
			(end -0.12065 -0.3048)
			(stroke
				(width 0.1)
				(type default)
			)
			(layer "B.Fab")
		)
		(fp_line
			(start 0.12065 -0.2794)
			(end -0.12065 -0.2794)
			(stroke
				(width 0.1)
				(type default)
			)
			(layer "B.Fab")
		)
		(fp_line
			(start -0.67945 -0.3048)
			(end -0.67945 0.3048)
			(stroke
				(width 0.1)
				(type default)
			)
			(layer "B.Fab")
		)
		(fp_line
			(start -0.12065 -0.3048)
			(end -0.67945 -0.3048)
			(stroke
				(width 0.1)
				(type default)
			)
			(layer "B.Fab")
		)
		(fp_line
			(start 0.12065 -0.305054)
			(end 0.12065 -0.2794)
			(stroke
				(width 0.1)
				(type default)
			)
			(layer "B.Fab")
		)
		(fp_line
			(start 0.67945 -0.305054)
			(end 0.12065 -0.305054)
			(stroke
				(width 0.1)
				(type default)
			)
			(layer "B.Fab")
		)
		(pad "1" smd circle
			(at 0.40005 0 90)
			(size 0 0)
			(layers "B.Cu" "B.Mask" "B.Paste")
			(net "PWRGD_DRAMPWRGD_CPU0_CD_LVC1_R2")
		)
		(pad "2" smd circle
			(at -0.40005 0 90)
			(size 0 0)
			(layers "B.Cu" "B.Mask" "B.Paste")
			(net "PWRGD_DRAMPWRGD_CPU0_CD_LVC1_R")
		)
	)
)
